FILE_TYPE = MULTI_PHYS_TABLE;
PART 'SLG55021'
{===============================================================================================================================================================================================================}
:PACK_TYPE | MATERIAL | PART_NUMBER     = EnvComp | PART_NUMBER  | JEDEC_TYPE        | DESCRIPTION                            | CLASS | COMPONENT_TYPE | HEIGHT     | LPID  |SPEED_URL  | Status |RPL| AML | Bus_Unit | Days ;
{===============================================================================================================================================================================================================}
'SM'       | 'IC'     | 'G56246-001'(!) = ''      | 'G56246-001' | 'DFN8_8_5MA'      | 'IC,LIN,DRVR,8,TDFN,SLG55021,FETDVR'   | 'IC'  | 'LCC'          | '0.031 IN' |'2554' | 'http://speed.intel.com:8081/speed/module/pdm/item/pdm_item_detail_direct.asp?item_cde=G56246-001&item_rev=01&url_param=unused' | '' | '' | '' | '' | '' 
'SM'       | 'EMPTY'  | 'G56246-001'(!) = ''      | 'G56246-001' | 'DFN8_8_5MA'      | 'IC,LIN,DRVR,8,TDFN,SLG55021,FETDVR'   | 'IO'  | 'LCC'          | '0.031 IN' |'2554' | 'http://speed.intel.com:8081/speed/module/pdm/item/pdm_item_detail_direct.asp?item_cde=G56246-001&item_rev=01&url_param=unused' | '' | '' | '' | '' | ''
END_PART
END.
